# T6G (Grand Teton) — schematic netlist excerpt (pin names and nets, part order shuffled) for the footprints in the layout excerpt that follows; sources: Cadence DE-HDL packaged netlist, KiCad conversion of 04192023_DAF0TMB3IC0_F0TG_MB_C_brd_V02_OCP.brd

PU49  ISL99390FRZTR5935  ISL99390FRZ-TR5935 IC  pkg QFN21_6X5XB  page 198
  VOS  = PVDDCR_SOC_P0_VOS1
  AGND  = GND
  VCC  = PVDDCR_SOC_P0_VCC1
  PVCC  = PVDDCR_CPU0_P0_PVCC
  PGND1  = GND
  GL1  = NC_PVDDCR_SOC_P0_GL1_1
  PGND2  = GND
  SW  = SW_PVDDCR_SOC_P0_SW1
  VIN1  = SW_P12V_AUX_PVDDCR_SOC_P0_FLT
  VIN2  = SW_P12V_AUX_PVDDCR_SOC_P0_FLT
  DNC  = NC_PVDDCR_SOC_P0_DNC1
  PHASE  = SW_PVDDCR_SOC_P0_PH1
  BOOT  = SW_PVDDCR_SOC_P0_BOOT1
  PWM  = PVDDCR_SOC_P0_PWM1
  EN  = PVDDCR_SOC_P0_VCC1
  TOUT_FLT  = PVDDCR_SOC_P0_TEMP1
  LSET  = PVDDCR_SOC_P0_LSET1
  IOUT  = PVDDCR_SOC_P0_IMON1
  REFIN  = PVDDCR_CPU0_P0_VCCS
  PGND3  = GND
  GL2  = NC_PVDDCR_SOC_P0_GL2_1

(kicad_pcb
	(version 20260206)
	(generator "pcbnew")
	(generator_version "10.0")
	(general
		(thickness 1.6)
		(legacy_teardrops no)
	)
	(paper "A4")
	(title_block
		(title "04192023_DAF0TMB3IC0_F0TG_MB_C_brd_V02_OCP.brd")
		(comment 1 "Grand Teton / footprints 2422-2422 of 8354")
	)
	(layers
		(0 "F.Cu" signal "TOP")
		(4 "In1.Cu" signal "GND")
		(6 "In2.Cu" signal "IN1")
		(8 "In3.Cu" signal "GND1")
		(10 "In4.Cu" signal "IN2")
		(12 "In5.Cu" signal "GND2")
		(14 "In6.Cu" signal "IN3")
		(16 "In7.Cu" signal "GND3")
		(18 "In8.Cu" signal "VCC")
		(20 "In9.Cu" signal "VCC1")
		(22 "In10.Cu" signal "GND4")
		(24 "In11.Cu" signal "IN4")
		(26 "In12.Cu" signal "GND5")
		(28 "In13.Cu" signal "IN5")
		(30 "In14.Cu" signal "GND6")
		(32 "In15.Cu" signal "IN6")
		(34 "In16.Cu" signal "GND7")
		(2 "B.Cu" signal "BOTTOM")
		(9 "F.Adhes" user "F.Adhesive")
		(11 "B.Adhes" user "B.Adhesive")
		(13 "F.Paste" user "Package Geometry/Pastemask Top")
		(15 "B.Paste" user "Package Geometry/Pastemask Bottom")
		(5 "F.SilkS" user "Ref Des/Silkscreen Top")
		(7 "B.SilkS" user "Ref Des/Silkscreen Bottom")
		(1 "F.Mask" user "Board Geometry/Soldermask Top")
		(3 "B.Mask" user "Board Geometry/Soldermask Bottom")
		(17 "Dwgs.User" user "User.Drawings")
		(19 "Cmts.User" user "User.Comments")
		(21 "Eco1.User" user "User.Eco1")
		(23 "Eco2.User" user "User.Eco2")
		(25 "Edge.Cuts" user "Board Geometry/Outline")
		(27 "Margin" user)
		(31 "F.CrtYd" user "Package Geometry/Place Bound Top")
		(29 "B.CrtYd" user "Package Geometry/Place Bound Bottom")
		(35 "F.Fab" user "Ref Des/Assembly Top")
		(33 "B.Fab" user "Ref Des/Assembly Bottom")
	)
	(footprint ""
		(layer "F.Cu")
		(at 397.824198 -177.171096 180)
		(property "Reference" "PU49"
			(at 4.331716 -6.338062 0)
			(unlocked yes)
			(layer "F.SilkS")
			(effects
				(font
					(size 0.7874 0.5842)
					(thickness 0.1524)
				)
				(justify left)
			)
		)
		(property "Value" ""
			(at 0 0 180)
			(layer "F.Fab")
			(effects
				(font
					(size 1.27 1.27)
				)
			)
		)
		(duplicate_pad_numbers_are_jumpers no)
		(fp_line
			(start 2.500122 2.999994)
			(end 2.2987 2.999994)
			(stroke
				(width 0.1524)
				(type default)
			)
			(layer "F.SilkS")
		)
		(fp_line
			(start 2.500122 2.339594)
			(end 2.500122 2.999994)
			(stroke
				(width 0.1524)
				(type default)
			)
			(layer "F.SilkS")
		)
		(fp_line
			(start 2.500122 -2.999994)
			(end 2.500122 -2.44348)
			(stroke
				(width 0.1524)
				(type default)
			)
			(layer "F.SilkS")
		)
		(fp_line
			(start 2.31394 -2.999994)
			(end 2.500122 -2.999994)
			(stroke
				(width 0.1524)
				(type default)
			)
			(layer "F.SilkS")
		)
		(fp_line
			(start -2.2987 2.999994)
			(end -2.500122 2.999994)
			(stroke
				(width 0.1524)
				(type default)
			)
			(layer "F.SilkS")
		)
		(fp_line
			(start -2.500122 2.999994)
			(end -2.500122 2.339594)
			(stroke
				(width 0.1524)
				(type default)
			)
			(layer "F.SilkS")
		)
		(fp_line
			(start -2.500122 0.6604)
			(end -2.500122 0.229108)
			(stroke
				(width 0.1524)
				(type default)
			)
			(layer "F.SilkS")
		)
		(fp_line
			(start -2.500122 -2.529078)
			(end -2.500122 -2.999994)
			(stroke
				(width 0.1524)
				(type default)
			)
			(layer "F.SilkS")
		)
		(fp_line
			(start -2.500122 -2.999994)
			(end -2.24409 -2.999994)
			(stroke
				(width 0.1524)
				(type default)
			)
			(layer "F.SilkS")
		)
		(fp_poly
			(pts
				(xy -2.695448 -2.471928) (xy -3.476244 -2.732278) (xy -2.955798 -3.252978)
			)
			(stroke
				(width 0)
				(type default)
			)
			(fill yes)
			(layer "F.SilkS")
		)
		(fp_line
			(start 2.500122 2.999994)
			(end -2.500122 2.999994)
			(stroke
				(width 0.1)
				(type default)
			)
			(layer "F.Fab")
		)
		(fp_line
			(start 2.500122 -2.999994)
			(end 2.500122 2.999994)
			(stroke
				(width 0.1)
				(type default)
			)
			(layer "F.Fab")
		)
		(fp_line
			(start -2.500122 2.999994)
			(end -2.500122 -2.999994)
			(stroke
				(width 0.1)
				(type default)
			)
			(layer "F.Fab")
		)
		(fp_line
			(start -2.500122 -2.999994)
			(end 2.500122 -2.999994)
			(stroke
				(width 0.1)
				(type default)
			)
			(layer "F.Fab")
		)
		(fp_poly
			(pts
				(xy -4.218432 -2.783078) (xy -4.218432 -1.767078) (xy -3.202432 -2.275078)
			)
			(stroke
				(width 0)
				(type default)
			)
			(fill yes)
			(layer "F.Fab")
		)
		(pad "1" smd rect
			(at -2.400046 -2.275078 270)
			(size 0.2286 0.6096)
			(layers "F.Cu" "F.Mask" "F.Paste")
			(net "PVDDCR_SOC_P0_VOS1")
		)
		(pad "2" smd rect
			(at -2.400046 -1.82499 270)
			(size 0.2286 0.6096)
			(layers "F.Cu" "F.Mask" "F.Paste")
			(net "GND")
		)
		(pad "3" smd rect
			(at -2.400046 -1.374902 270)
			(size 0.2286 0.6096)
			(layers "F.Cu" "F.Mask" "F.Paste")
			(net "PVDDCR_SOC_P0_VCC1")
		)
		(pad "4" smd rect
			(at -2.400046 -0.925068 270)
			(size 0.2286 0.6096)
			(layers "F.Cu" "F.Mask" "F.Paste")
			(net "PVDDCR_CPU0_P0_PVCC")
		)
		(pad "5" smd rect
			(at -2.400046 -0.47498 270)
			(size 0.2286 0.6096)
			(layers "F.Cu" "F.Mask" "F.Paste")
			(net "GND")
		)
		(pad "6" smd rect
			(at -2.400046 -0.024892 270)
			(size 0.2286 0.6096)
			(layers "F.Cu" "F.Mask" "F.Paste")
			(net "NC_PVDDCR_SOC_P0_GL1_1")
		)
		(pad "7_9-20_24" smd circle
			(at 0 1.150112 270)
			(size 0 0)
			(layers "F.Cu" "F.Mask" "F.Paste")
			(net "GND")
		)
		(pad "10_19" smd rect
			(at 0 2.899918 270)
			(size 0.6096 4.318)
			(layers "F.Cu" "F.Mask" "F.Paste")
			(net "SW_PVDDCR_SOC_P0_SW1")
		)
		(pad "25_29" smd rect
			(at 1.549908 -1.279906 90)
			(size 2.0574 2.3114)
			(layers "F.Cu" "F.Mask" "F.Paste")
			(net "SW_P12V_AUX_PVDDCR_SOC_P0_FLT")
		)
		(pad "30" smd rect
			(at 2.05994 -2.899918 180)
			(size 0.2286 0.6096)
			(layers "F.Cu" "F.Mask" "F.Paste")
			(net "SW_P12V_AUX_PVDDCR_SOC_P0_FLT")
		)
		(pad "31" smd rect
			(at 1.610106 -2.899918 180)
			(size 0.2286 0.6096)
			(layers "F.Cu" "F.Mask" "F.Paste")
			(net "NC_PVDDCR_SOC_P0_DNC1")
		)
		(pad "32" smd rect
			(at 1.160018 -2.899918 180)
			(size 0.2286 0.6096)
			(layers "F.Cu" "F.Mask" "F.Paste")
			(net "SW_PVDDCR_SOC_P0_PH1")
		)
		(pad "33" smd rect
			(at 0.70993 -2.899918 180)
			(size 0.2286 0.6096)
			(layers "F.Cu" "F.Mask" "F.Paste")
			(net "SW_PVDDCR_SOC_P0_BOOT1")
		)
		(pad "34" smd rect
			(at 0.260096 -2.899918 180)
			(size 0.2286 0.6096)
			(layers "F.Cu" "F.Mask" "F.Paste")
			(net "PVDDCR_SOC_P0_PWM1")
		)
		(pad "35" smd rect
			(at -0.189992 -2.899918 180)
			(size 0.2286 0.6096)
			(layers "F.Cu" "F.Mask" "F.Paste")
			(net "PVDDCR_SOC_P0_VCC1")
		)
		(pad "36" smd rect
			(at -0.64008 -2.899918 180)
			(size 0.2286 0.6096)
			(layers "F.Cu" "F.Mask" "F.Paste")
			(net "PVDDCR_SOC_P0_TEMP1")
		)
		(pad "37" smd rect
			(at -1.089914 -2.899918 180)
			(size 0.2286 0.6096)
			(layers "F.Cu" "F.Mask" "F.Paste")
			(net "PVDDCR_SOC_P0_LSET1")
		)
		(pad "38" smd rect
			(at -1.540002 -2.899918 180)
			(size 0.2286 0.6096)
			(layers "F.Cu" "F.Mask" "F.Paste")
			(net "PVDDCR_SOC_P0_IMON1")
		)
		(pad "39" smd rect
			(at -1.99009 -2.899918 180)
			(size 0.2286 0.6096)
			(layers "F.Cu" "F.Mask" "F.Paste")
			(net "PVDDCR_CPU0_P0_VCCS")
		)
		(pad "40" smd rect
			(at -0.87503 -1.27508 180)
			(size 1.7526 1.9558)
			(layers "F.Cu" "F.Mask" "F.Paste")
			(net "GND")
		)
		(pad "41" smd rect
			(at -1.525016 0.249936 90)
			(size 0.3048 0.4572)
			(layers "F.Cu" "F.Mask" "F.Paste")
			(net "NC_PVDDCR_SOC_P0_GL2_1")
		)
		(zone
			(layer "F.Cu")
			(hatch none 0.5)
			(connect_pads
				(clearance 0)
			)
			(min_thickness 0.25)
			(keepout
				(tracks not_allowed)
				(vias allowed)
				(pads allowed)
				(copperpour not_allowed)
				(footprints allowed)
			)
			(placement
				(enabled no)
				(sheetname "")
			)
			(fill
				(thermal_gap 0.5)
				(thermal_bridge_width 0.5)
				(island_removal_mode 0)
			)
			(polygon
				(pts
					(xy 400.32432 -179.75453) (xy 400.32432 -179.42179) (xy 395.324076 -179.42179) (xy 395.324076 -179.747418)
					(xy 395.614398 -179.747418) (xy 395.614398 -179.715414) (xy 400.033998 -179.715414) (xy 400.033998 -179.75453)
				)
			)
		)
		(zone
			(layer "F.Cu")
			(hatch none 0.5)
			(connect_pads
				(clearance 0)
			)
			(min_thickness 0.25)
			(keepout
				(tracks not_allowed)
				(vias allowed)
				(pads allowed)
				(copperpour not_allowed)
				(footprints allowed)
			)
			(placement
				(enabled no)
				(sheetname "")
			)
			(fill
				(thermal_gap 0.5)
				(thermal_bridge_width 0.5)
				(island_removal_mode 0)
			)
			(polygon
				(pts
					(xy 397.772128 -176.924716) (xy 397.772128 -174.867316) (xy 399.626328 -174.867316) (xy 399.626328 -175.108362)
					(xy 399.868644 -175.108362) (xy 399.868644 -174.626778) (xy 395.960346 -174.626778) (xy 395.960346 -174.81169)
					(xy 397.48079 -174.81169) (xy 397.48079 -176.97069) (xy 395.324076 -176.97069) (xy 395.324076 -177.220372)
					(xy 397.472408 -177.220372) (xy 397.74876 -176.94402) (xy 397.752824 -176.94402)
				)
			)
		)
	)
)
